(kicad_pcb
	(version 20260206)
	(generator "pcbnew")
	(generator_version "10.0")
	(general
		(thickness 1.6)
		(legacy_teardrops no)
	)
	(paper "A4")
	(title_block
		(title "03242023_DA0F0TMBIJ0_F0T_Motherboard_J_brd_V01_OCP.brd")
		(comment 1 "Grand Teton / footprints 2134-2139 of 6105")
	)
	(layers
		(0 "F.Cu" signal "TOP")
		(4 "In1.Cu" signal "GND")
		(6 "In2.Cu" signal "IN1")
		(8 "In3.Cu" signal "GND1")
		(10 "In4.Cu" signal "IN2")
		(12 "In5.Cu" signal "GND2")
		(14 "In6.Cu" signal "IN3")
		(16 "In7.Cu" signal "GND3")
		(18 "In8.Cu" signal "VCC")
		(20 "In9.Cu" signal "VCC1")
		(22 "In10.Cu" signal "GND4")
		(24 "In11.Cu" signal "IN4")
		(26 "In12.Cu" signal "GND5")
		(28 "In13.Cu" signal "IN5")
		(30 "In14.Cu" signal "GND6")
		(32 "In15.Cu" signal "IN6")
		(34 "In16.Cu" signal "GND7")
		(2 "B.Cu" signal "BOTTOM")
		(9 "F.Adhes" user "F.Adhesive")
		(11 "B.Adhes" user "B.Adhesive")
		(13 "F.Paste" user "Package Geometry/Pastemask Top")
		(15 "B.Paste" user "Package Geometry/Pastemask Bottom")
		(5 "F.SilkS" user "Ref Des/Silkscreen Top")
		(7 "B.SilkS" user "Ref Des/Silkscreen Bottom")
		(1 "F.Mask" user "Board Geometry/Soldermask Top")
		(3 "B.Mask" user "Board Geometry/Soldermask Bottom")
		(17 "Dwgs.User" user "User.Drawings")
		(19 "Cmts.User" user "User.Comments")
		(21 "Eco1.User" user "User.Eco1")
		(23 "Eco2.User" user "User.Eco2")
		(25 "Edge.Cuts" user "Board Geometry/Outline")
		(27 "Margin" user)
		(31 "F.CrtYd" user "Package Geometry/Place Bound Top")
		(29 "B.CrtYd" user "Package Geometry/Place Bound Bottom")
		(35 "F.Fab" user "Ref Des/Assembly Top")
		(33 "B.Fab" user "Ref Des/Assembly Bottom")
	)
	(footprint ""
		(layer "F.Cu")
		(at 239.152684 -52.01285 180)
		(property "Reference" "C1995"
			(at 0 0 180)
			(layer "F.SilkS")
			(hide yes)
			(effects
				(font
					(size 1.27 1.27)
				)
			)
		)
		(property "Value" ""
			(at 0 0 180)
			(layer "F.Fab")
			(effects
				(font
					(size 1.27 1.27)
				)
			)
		)
		(duplicate_pad_numbers_are_jumpers no)
		(fp_line
			(start 0.299974 0.150114)
			(end -0.299974 0.150114)
			(stroke
				(width 0.1)
				(type default)
			)
			(layer "F.Fab")
		)
		(fp_line
			(start 0.299974 -0.150114)
			(end 0.299974 0.150114)
			(stroke
				(width 0.1)
				(type default)
			)
			(layer "F.Fab")
		)
		(fp_line
			(start -0.299974 0.150114)
			(end -0.299974 -0.150114)
			(stroke
				(width 0.1)
				(type default)
			)
			(layer "F.Fab")
		)
		(fp_line
			(start -0.299974 -0.150114)
			(end 0.299974 -0.150114)
			(stroke
				(width 0.1)
				(type default)
			)
			(layer "F.Fab")
		)
		(pad "1" smd rect
			(at -0.2667 0 180)
			(size 0.3048 0.381)
			(layers "F.Cu" "F.Mask" "F.Paste")
			(net "P3E_PCH_E1S_TX_DP<0>")
		)
		(pad "2" smd rect
			(at 0.2667 0 180)
			(size 0.3048 0.381)
			(layers "F.Cu" "F.Mask" "F.Paste")
			(net "P3E_PCH_E1S_TX_C_DP<0>")
		)
		(zone
			(layer "In1.Cu")
			(hatch none 0.5)
			(connect_pads
				(clearance 0)
			)
			(min_thickness 0.25)
			(keepout
				(tracks not_allowed)
				(vias allowed)
				(pads allowed)
				(copperpour not_allowed)
				(footprints allowed)
			)
			(placement
				(enabled no)
				(sheetname "")
			)
			(fill
				(thermal_gap 0.5)
				(thermal_bridge_width 0.5)
				(island_removal_mode 0)
			)
			(polygon
				(pts
					(arc
						(start 239.012984 -52.253134)
						(mid 239.066866 -52.230816)
						(end 239.089184 -52.176934)
					)
					(arc
						(start 239.089184 -51.846734)
						(mid 239.066866 -51.792852)
						(end 239.012984 -51.770534)
					)
					(arc
						(start 238.758984 -51.770534)
						(mid 238.705102 -51.792852)
						(end 238.682784 -51.846734)
					)
					(arc
						(start 238.682784 -52.176934)
						(mid 238.705102 -52.230816)
						(end 238.758984 -52.253134)
					)
				)
			)
		)
		(zone
			(layer "In1.Cu")
			(hatch none 0.5)
			(connect_pads
				(clearance 0)
			)
			(min_thickness 0.25)
			(keepout
				(tracks not_allowed)
				(vias allowed)
				(pads allowed)
				(copperpour not_allowed)
				(footprints allowed)
			)
			(placement
				(enabled no)
				(sheetname "")
			)
			(fill
				(thermal_gap 0.5)
				(thermal_bridge_width 0.5)
				(island_removal_mode 0)
			)
			(polygon
				(pts
					(arc
						(start 239.546384 -52.253134)
						(mid 239.600266 -52.230816)
						(end 239.622584 -52.176934)
					)
					(arc
						(start 239.622584 -51.846734)
						(mid 239.600266 -51.792852)
						(end 239.546384 -51.770534)
					)
					(arc
						(start 239.292384 -51.770534)
						(mid 239.238502 -51.792852)
						(end 239.216184 -51.846734)
					)
					(arc
						(start 239.216184 -52.176934)
						(mid 239.238502 -52.230816)
						(end 239.292384 -52.253134)
					)
				)
			)
		)
	)
	(footprint ""
		(layer "F.Cu")
		(at 122.61088 -96.230948 -90)
		(property "Reference" "Q138"
			(at -4.130802 0.18288 0)
			(unlocked yes)
			(layer "F.SilkS")
			(effects
				(font
					(size 0.635 0.4064)
					(thickness 0.1524)
				)
			)
		)
		(property "Value" ""
			(at 0 0 270)
			(layer "F.Fab")
			(effects
				(font
					(size 1.27 1.27)
				)
			)
		)
		(duplicate_pad_numbers_are_jumpers no)
		(fp_line
			(start -1.376172 1.199896)
			(end -1.376172 -1.199896)
			(stroke
				(width 0.1524)
				(type default)
			)
			(layer "F.SilkS")
		)
		(fp_line
			(start 1.376172 1.199896)
			(end -1.376172 1.199896)
			(stroke
				(width 0.1524)
				(type default)
			)
			(layer "F.SilkS")
		)
		(fp_line
			(start 0 -0.762)
			(end 0.508 -1.199896)
			(stroke
				(width 0.1524)
				(type default)
			)
			(layer "F.SilkS")
		)
		(fp_line
			(start -1.376172 -1.199896)
			(end -0.508 -1.199896)
			(stroke
				(width 0.1524)
				(type default)
			)
			(layer "F.SilkS")
		)
		(fp_line
			(start -0.508 -1.199896)
			(end 0 -0.762)
			(stroke
				(width 0.1524)
				(type default)
			)
			(layer "F.SilkS")
		)
		(fp_line
			(start 0.508 -1.199896)
			(end 1.376172 -1.199896)
			(stroke
				(width 0.1524)
				(type default)
			)
			(layer "F.SilkS")
		)
		(fp_line
			(start 1.376172 -1.199896)
			(end 1.376172 1.199896)
			(stroke
				(width 0.1524)
				(type default)
			)
			(layer "F.SilkS")
		)
		(fp_poly
			(pts
				(xy -1.5875 -1.0033) (xy -2.3495 -1.3843) (xy -2.3495 -0.6223)
			)
			(stroke
				(width 0)
				(type default)
			)
			(fill yes)
			(layer "F.SilkS")
		)
		(fp_line
			(start -0.674878 1.100074)
			(end -0.674878 -1.100074)
			(stroke
				(width 0.1)
				(type default)
			)
			(layer "F.Fab")
		)
		(fp_line
			(start 0.674878 1.100074)
			(end -0.674878 1.100074)
			(stroke
				(width 0.1)
				(type default)
			)
			(layer "F.Fab")
		)
		(fp_line
			(start -0.674878 -1.100074)
			(end 0.674878 -1.100074)
			(stroke
				(width 0.1)
				(type default)
			)
			(layer "F.Fab")
		)
		(fp_line
			(start 0.674878 -1.100074)
			(end 0.674878 1.100074)
			(stroke
				(width 0.1)
				(type default)
			)
			(layer "F.Fab")
		)
		(fp_poly
			(pts
				(xy -1.4605 -0.7493) (xy -2.2225 -1.1303) (xy -2.2225 -0.3683)
			)
			(stroke
				(width 0)
				(type default)
			)
			(fill yes)
			(layer "F.Fab")
		)
		(pad "1" smd rect
			(at -0.899922 -0.750062 180)
			(size 0.6096 0.6096)
			(layers "F.Cu" "F.Mask" "F.Paste")
			(net "GND")
		)
		(pad "2" smd rect
			(at -0.899922 0 180)
			(size 0.4064 0.6096)
			(layers "F.Cu" "F.Mask" "F.Paste")
			(net "H_CPU0_THERMTRIP_R_N")
		)
		(pad "3" smd rect
			(at -0.899922 0.750062 180)
			(size 0.6096 0.6096)
			(layers "F.Cu" "F.Mask" "F.Paste")
			(net "H_CPU0_THERMTRIP_N")
		)
		(pad "4" smd rect
			(at 0.899922 0.750062 180)
			(size 0.6096 0.6096)
			(layers "F.Cu" "F.Mask" "F.Paste")
			(net "PVNN_TERM_CPU0")
		)
		(pad "5" smd rect
			(at 0.899922 0 180)
			(size 0.4064 0.6096)
			(layers "F.Cu" "F.Mask" "F.Paste")
			(net "H_CPU0_THERMTRIP_VT_R_N")
		)
		(pad "6" smd rect
			(at 0.899922 -0.750062 180)
			(size 0.6096 0.6096)
			(layers "F.Cu" "F.Mask" "F.Paste")
			(net "H_CPU0_THERMTRIP_VT_N")
		)
	)
	(footprint ""
		(layer "F.Cu")
		(at 35.577018 -436.903368 180)
		(property "Reference" "C1796"
			(at 0 0 180)
			(layer "F.SilkS")
			(hide yes)
			(effects
				(font
					(size 1.27 1.27)
				)
			)
		)
		(property "Value" ""
			(at 0 0 180)
			(layer "F.Fab")
			(effects
				(font
					(size 1.27 1.27)
				)
			)
		)
		(duplicate_pad_numbers_are_jumpers no)
		(fp_line
			(start 0.7874 0.4064)
			(end -0.7874 0.4064)
			(stroke
				(width 0.1524)
				(type default)
			)
			(layer "F.SilkS")
		)
		(fp_line
			(start 0.7874 -0.4064)
			(end 0.7874 0.4064)
			(stroke
				(width 0.1524)
				(type default)
			)
			(layer "F.SilkS")
		)
		(fp_line
			(start -0.7874 0.4064)
			(end -0.7874 -0.4064)
			(stroke
				(width 0.1524)
				(type default)
			)
			(layer "F.SilkS")
		)
		(fp_line
			(start -0.7874 -0.4064)
			(end 0.7874 -0.4064)
			(stroke
				(width 0.1524)
				(type default)
			)
			(layer "F.SilkS")
		)
		(fp_line
			(start 0.67945 0.3048)
			(end 0.120396 0.3048)
			(stroke
				(width 0.1)
				(type default)
			)
			(layer "F.Fab")
		)
		(fp_line
			(start 0.67945 -0.3048)
			(end 0.67945 0.3048)
			(stroke
				(width 0.1)
				(type default)
			)
			(layer "F.Fab")
		)
		(fp_line
			(start 0.12065 -0.2794)
			(end 0.12065 -0.3048)
			(stroke
				(width 0.1)
				(type default)
			)
			(layer "F.Fab")
		)
		(fp_line
			(start 0.12065 -0.3048)
			(end 0.67945 -0.3048)
			(stroke
				(width 0.1)
				(type default)
			)
			(layer "F.Fab")
		)
		(fp_line
			(start 0.120396 0.3048)
			(end 0.120396 0.2794)
			(stroke
				(width 0.1)
				(type default)
			)
			(layer "F.Fab")
		)
		(fp_line
			(start 0.120396 0.2794)
			(end -0.12065 0.2794)
			(stroke
				(width 0.1)
				(type default)
			)
			(layer "F.Fab")
		)
		(fp_line
			(start -0.12065 0.3048)
			(end -0.67945 0.3048)
			(stroke
				(width 0.1)
				(type default)
			)
			(layer "F.Fab")
		)
		(fp_line
			(start -0.12065 0.2794)
			(end -0.12065 0.3048)
			(stroke
				(width 0.1)
				(type default)
			)
			(layer "F.Fab")
		)
		(fp_line
			(start -0.12065 -0.2794)
			(end 0.12065 -0.2794)
			(stroke
				(width 0.1)
				(type default)
			)
			(layer "F.Fab")
		)
		(fp_line
			(start -0.12065 -0.305054)
			(end -0.12065 -0.2794)
			(stroke
				(width 0.1)
				(type default)
			)
			(layer "F.Fab")
		)
		(fp_line
			(start -0.67945 0.3048)
			(end -0.67945 -0.305054)
			(stroke
				(width 0.1)
				(type default)
			)
			(layer "F.Fab")
		)
		(fp_line
			(start -0.67945 -0.305054)
			(end -0.12065 -0.305054)
			(stroke
				(width 0.1)
				(type default)
			)
			(layer "F.Fab")
		)
		(pad "1" smd circle
			(at -0.40005 0 180)
			(size 0 0)
			(layers "F.Cu" "F.Mask" "F.Paste")
			(net "P3V3_AUX")
		)
		(pad "2" smd circle
			(at 0.40005 0 180)
			(size 0 0)
			(layers "F.Cu" "F.Mask" "F.Paste")
			(net "GND")
		)
	)
	(footprint ""
		(layer "F.Cu")
		(at 445.157098 -92.468192 180)
		(property "Reference" "R3628"
			(at 0 0 180)
			(layer "F.SilkS")
			(hide yes)
			(effects
				(font
					(size 1.27 1.27)
				)
			)
		)
		(property "Value" ""
			(at 0 0 180)
			(layer "F.Fab")
			(effects
				(font
					(size 1.27 1.27)
				)
			)
		)
		(duplicate_pad_numbers_are_jumpers no)
		(fp_line
			(start 0.7874 0.4064)
			(end -0.7874 0.4064)
			(stroke
				(width 0.1524)
				(type default)
			)
			(layer "F.SilkS")
		)
		(fp_line
			(start 0.7874 -0.4064)
			(end 0.7874 0.4064)
			(stroke
				(width 0.1524)
				(type default)
			)
			(layer "F.SilkS")
		)
		(fp_line
			(start -0.7874 0.4064)
			(end -0.7874 -0.4064)
			(stroke
				(width 0.1524)
				(type default)
			)
			(layer "F.SilkS")
		)
		(fp_line
			(start -0.7874 -0.4064)
			(end 0.7874 -0.4064)
			(stroke
				(width 0.1524)
				(type default)
			)
			(layer "F.SilkS")
		)
		(fp_line
			(start 0.67945 0.3048)
			(end 0.120396 0.3048)
			(stroke
				(width 0.1)
				(type default)
			)
			(layer "F.Fab")
		)
		(fp_line
			(start 0.67945 -0.3048)
			(end 0.67945 0.3048)
			(stroke
				(width 0.1)
				(type default)
			)
			(layer "F.Fab")
		)
		(fp_line
			(start 0.12065 -0.2794)
			(end 0.12065 -0.3048)
			(stroke
				(width 0.1)
				(type default)
			)
			(layer "F.Fab")
		)
		(fp_line
			(start 0.12065 -0.3048)
			(end 0.67945 -0.3048)
			(stroke
				(width 0.1)
				(type default)
			)
			(layer "F.Fab")
		)
		(fp_line
			(start 0.120396 0.3048)
			(end 0.120396 0.2794)
			(stroke
				(width 0.1)
				(type default)
			)
			(layer "F.Fab")
		)
		(fp_line
			(start 0.120396 0.2794)
			(end -0.12065 0.2794)
			(stroke
				(width 0.1)
				(type default)
			)
			(layer "F.Fab")
		)
		(fp_line
			(start -0.12065 0.3048)
			(end -0.67945 0.3048)
			(stroke
				(width 0.1)
				(type default)
			)
			(layer "F.Fab")
		)
		(fp_line
			(start -0.12065 0.2794)
			(end -0.12065 0.3048)
			(stroke
				(width 0.1)
				(type default)
			)
			(layer "F.Fab")
		)
		(fp_line
			(start -0.12065 -0.2794)
			(end 0.12065 -0.2794)
			(stroke
				(width 0.1)
				(type default)
			)
			(layer "F.Fab")
		)
		(fp_line
			(start -0.12065 -0.305054)
			(end -0.12065 -0.2794)
			(stroke
				(width 0.1)
				(type default)
			)
			(layer "F.Fab")
		)
		(fp_line
			(start -0.67945 0.3048)
			(end -0.67945 -0.305054)
			(stroke
				(width 0.1)
				(type default)
			)
			(layer "F.Fab")
		)
		(fp_line
			(start -0.67945 -0.305054)
			(end -0.12065 -0.305054)
			(stroke
				(width 0.1)
				(type default)
			)
			(layer "F.Fab")
		)
		(pad "1" smd circle
			(at -0.40005 0 180)
			(size 0 0)
			(layers "F.Cu" "F.Mask" "F.Paste")
			(net "P3V3_AUX")
		)
		(pad "2" smd circle
			(at 0.40005 0 180)
			(size 0 0)
			(layers "F.Cu" "F.Mask" "F.Paste")
			(net "INA230_1_A1")
		)
	)
	(footprint ""
		(layer "F.Cu")
		(at 366.18672 -403.957028)
		(property "Reference" "C1803"
			(at 0 0 0)
			(layer "F.SilkS")
			(hide yes)
			(effects
				(font
					(size 1.27 1.27)
				)
			)
		)
		(property "Value" ""
			(at 0 0 0)
			(layer "F.Fab")
			(effects
				(font
					(size 1.27 1.27)
				)
			)
		)
		(duplicate_pad_numbers_are_jumpers no)
		(fp_line
			(start -0.7874 -0.4064)
			(end 0.7874 -0.4064)
			(stroke
				(width 0.1524)
				(type default)
			)
			(layer "F.SilkS")
		)
		(fp_line
			(start -0.7874 0.4064)
			(end -0.7874 -0.4064)
			(stroke
				(width 0.1524)
				(type default)
			)
			(layer "F.SilkS")
		)
		(fp_line
			(start 0.7874 -0.4064)
			(end 0.7874 0.4064)
			(stroke
				(width 0.1524)
				(type default)
			)
			(layer "F.SilkS")
		)
		(fp_line
			(start 0.7874 0.4064)
			(end -0.7874 0.4064)
			(stroke
				(width 0.1524)
				(type default)
			)
			(layer "F.SilkS")
		)
		(fp_line
			(start -0.67945 -0.305054)
			(end -0.12065 -0.305054)
			(stroke
				(width 0.1)
				(type default)
			)
			(layer "F.Fab")
		)
		(fp_line
			(start -0.67945 0.3048)
			(end -0.67945 -0.305054)
			(stroke
				(width 0.1)
				(type default)
			)
			(layer "F.Fab")
		)
		(fp_line
			(start -0.12065 -0.305054)
			(end -0.12065 -0.2794)
			(stroke
				(width 0.1)
				(type default)
			)
			(layer "F.Fab")
		)
		(fp_line
			(start -0.12065 -0.2794)
			(end 0.12065 -0.2794)
			(stroke
				(width 0.1)
				(type default)
			)
			(layer "F.Fab")
		)
		(fp_line
			(start -0.12065 0.2794)
			(end -0.12065 0.3048)
			(stroke
				(width 0.1)
				(type default)
			)
			(layer "F.Fab")
		)
		(fp_line
			(start -0.12065 0.3048)
			(end -0.67945 0.3048)
			(stroke
				(width 0.1)
				(type default)
			)
			(layer "F.Fab")
		)
		(fp_line
			(start 0.120396 0.2794)
			(end -0.12065 0.2794)
			(stroke
				(width 0.1)
				(type default)
			)
			(layer "F.Fab")
		)
		(fp_line
			(start 0.120396 0.3048)
			(end 0.120396 0.2794)
			(stroke
				(width 0.1)
				(type default)
			)
			(layer "F.Fab")
		)
		(fp_line
			(start 0.12065 -0.3048)
			(end 0.67945 -0.3048)
			(stroke
				(width 0.1)
				(type default)
			)
			(layer "F.Fab")
		)
		(fp_line
			(start 0.12065 -0.2794)
			(end 0.12065 -0.3048)
			(stroke
				(width 0.1)
				(type default)
			)
			(layer "F.Fab")
		)
		(fp_line
			(start 0.67945 -0.3048)
			(end 0.67945 0.3048)
			(stroke
				(width 0.1)
				(type default)
			)
			(layer "F.Fab")
		)
		(fp_line
			(start 0.67945 0.3048)
			(end 0.120396 0.3048)
			(stroke
				(width 0.1)
				(type default)
			)
			(layer "F.Fab")
		)
		(pad "1" smd circle
			(at -0.40005 0)
			(size 0 0)
			(layers "F.Cu" "F.Mask" "F.Paste")
			(net "P3V3_AUX")
		)
		(pad "2" smd circle
			(at 0.40005 0)
			(size 0 0)
			(layers "F.Cu" "F.Mask" "F.Paste")
			(net "GND")
		)
	)
	(footprint ""
		(layer "F.Cu")
		(at 116.561616 -240.277142 90)
		(property "Reference" "C302"
			(at 0 0 90)
			(layer "F.SilkS")
			(hide yes)
			(effects
				(font
					(size 1.27 1.27)
				)
			)
		)
		(property "Value" ""
			(at 0 0 90)
			(layer "F.Fab")
			(effects
				(font
					(size 1.27 1.27)
				)
			)
		)
		(duplicate_pad_numbers_are_jumpers no)
		(fp_line
			(start 0.7874 -0.4064)
			(end 0.7874 0.4064)
			(stroke
				(width 0.1524)
				(type default)
			)
			(layer "F.SilkS")
		)
		(fp_line
			(start -0.7874 -0.4064)
			(end 0.7874 -0.4064)
			(stroke
				(width 0.1524)
				(type default)
			)
			(layer "F.SilkS")
		)
		(fp_line
			(start 0.7874 0.4064)
			(end -0.7874 0.4064)
			(stroke
				(width 0.1524)
				(type default)
			)
			(layer "F.SilkS")
		)
		(fp_line
			(start -0.7874 0.4064)
			(end -0.7874 -0.4064)
			(stroke
				(width 0.1524)
				(type default)
			)
			(layer "F.SilkS")
		)
		(fp_line
			(start -0.12065 -0.305054)
			(end -0.12065 -0.2794)
			(stroke
				(width 0.1)
				(type default)
			)
			(layer "F.Fab")
		)
		(fp_line
			(start -0.67945 -0.305054)
			(end -0.12065 -0.305054)
			(stroke
				(width 0.1)
				(type default)
			)
			(layer "F.Fab")
		)
		(fp_line
			(start 0.67945 -0.3048)
			(end 0.67945 0.3048)
			(stroke
				(width 0.1)
				(type default)
			)
			(layer "F.Fab")
		)
		(fp_line
			(start 0.12065 -0.3048)
			(end 0.67945 -0.3048)
			(stroke
				(width 0.1)
				(type default)
			)
			(layer "F.Fab")
		)
		(fp_line
			(start 0.12065 -0.2794)
			(end 0.12065 -0.3048)
			(stroke
				(width 0.1)
				(type default)
			)
			(layer "F.Fab")
		)
		(fp_line
			(start -0.12065 -0.2794)
			(end 0.12065 -0.2794)
			(stroke
				(width 0.1)
				(type default)
			)
			(layer "F.Fab")
		)
		(fp_line
			(start 0.120396 0.2794)
			(end -0.12065 0.2794)
			(stroke
				(width 0.1)
				(type default)
			)
			(layer "F.Fab")
		)
		(fp_line
			(start -0.12065 0.2794)
			(end -0.12065 0.3048)
			(stroke
				(width 0.1)
				(type default)
			)
			(layer "F.Fab")
		)
		(fp_line
			(start 0.67945 0.3048)
			(end 0.120396 0.3048)
			(stroke
				(width 0.1)
				(type default)
			)
			(layer "F.Fab")
		)
		(fp_line
			(start 0.120396 0.3048)
			(end 0.120396 0.2794)
			(stroke
				(width 0.1)
				(type default)
			)
			(layer "F.Fab")
		)
		(fp_line
			(start -0.12065 0.3048)
			(end -0.67945 0.3048)
			(stroke
				(width 0.1)
				(type default)
			)
			(layer "F.Fab")
		)
		(fp_line
			(start -0.67945 0.3048)
			(end -0.67945 -0.305054)
			(stroke
				(width 0.1)
				(type default)
			)
			(layer "F.Fab")
		)
		(pad "1" smd circle
			(at -0.40005 0 90)
			(size 0 0)
			(layers "F.Cu" "F.Mask" "F.Paste")
			(net "PVCCIN_CPU1")
		)
		(pad "2" smd circle
			(at 0.40005 0 90)
			(size 0 0)
			(layers "F.Cu" "F.Mask" "F.Paste")
			(net "GND")
		)
	)
)
